(kicad_pcb
	(version 20260206)
	(generator "pcbnew")
	(generator_version "10.0")
	(general
		(thickness 1.6)
		(legacy_teardrops no)
	)
	(paper "A4")
	(title_block
		(title "v1-chassis-manager — T6M_CM_d_v01_1031_1645.brd")
		(comment 1 "Open CloudServer (Microsoft) / footprints 19-25 of 2512")
	)
	(layers
		(0 "F.Cu" signal "TOP")
		(4 "In1.Cu" signal "GND1")
		(6 "In2.Cu" signal "IN1")
		(8 "In3.Cu" signal "VCC1")
		(10 "In4.Cu" signal "VCC2")
		(12 "In5.Cu" signal "GND2")
		(14 "In6.Cu" signal "IN2")
		(16 "In7.Cu" signal "IN3")
		(18 "In8.Cu" signal "GND3")
		(2 "B.Cu" signal "BOTTOM")
		(9 "F.Adhes" user "F.Adhesive")
		(11 "B.Adhes" user "B.Adhesive")
		(13 "F.Paste" user "Package Geometry/Pastemask Top")
		(15 "B.Paste" user "Package Geometry/Pastemask Bottom")
		(5 "F.SilkS" user "Ref Des/Silkscreen Top")
		(7 "B.SilkS" user "Ref Des/Silkscreen Bottom")
		(1 "F.Mask" user "Board Geometry/Soldermask Top")
		(3 "B.Mask" user "Board Geometry/Soldermask Bottom")
		(17 "Dwgs.User" user "User.Drawings")
		(19 "Cmts.User" user "User.Comments")
		(21 "Eco1.User" user "User.Eco1")
		(23 "Eco2.User" user "User.Eco2")
		(25 "Edge.Cuts" user "Board Geometry/Outline")
		(27 "Margin" user)
		(31 "F.CrtYd" user "Package Geometry/Place Bound Top")
		(29 "B.CrtYd" user "Package Geometry/Place Bound Bottom")
		(35 "F.Fab" user "Ref Des/Assembly Top")
		(33 "B.Fab" user "Ref Des/Assembly Bottom")
	)
	(footprint ""
		(layer "F.Cu")
		(at 31.641288 -128.354582)
		(property "Reference" "U121"
			(at -6.505448 3.244088 0)
			(unlocked yes)
			(layer "F.SilkS")
			(effects
				(font
					(size 0.7874 0.5842)
					(thickness 0.1524)
				)
				(justify left)
			)
		)
		(property "Value" ""
			(at 0 0 0)
			(layer "F.Fab")
			(effects
				(font
					(size 1.27 1.27)
				)
			)
		)
		(duplicate_pad_numbers_are_jumpers no)
		(fp_line
			(start -2.525014 0.025146)
			(end -2.525014 0.661162)
			(stroke
				(width 0.1524)
				(type default)
			)
			(layer "F.SilkS")
		)
		(fp_line
			(start -2.525014 2.540762)
			(end -2.525014 3.075178)
			(stroke
				(width 0.1524)
				(type default)
			)
			(layer "F.SilkS")
		)
		(fp_line
			(start -2.525014 3.075178)
			(end -2.525014 0.025146)
			(stroke
				(width 0.1524)
				(type default)
			)
			(layer "F.SilkS")
		)
		(fp_line
			(start -2.525014 3.075178)
			(end -2.320798 3.075178)
			(stroke
				(width 0.1524)
				(type default)
			)
			(layer "F.SilkS")
		)
		(fp_line
			(start -2.320798 0.025146)
			(end -2.525014 0.025146)
			(stroke
				(width 0.1524)
				(type default)
			)
			(layer "F.SilkS")
		)
		(fp_line
			(start 0.320802 3.075178)
			(end 0.525018 3.075178)
			(stroke
				(width 0.1524)
				(type default)
			)
			(layer "F.SilkS")
		)
		(fp_line
			(start 0.525018 0.025146)
			(end 0.320802 0.025146)
			(stroke
				(width 0.1524)
				(type default)
			)
			(layer "F.SilkS")
		)
		(fp_line
			(start 0.525018 0.686562)
			(end 0.525018 0.025146)
			(stroke
				(width 0.1524)
				(type default)
			)
			(layer "F.SilkS")
		)
		(fp_line
			(start 0.525018 3.075178)
			(end 0.525018 0.025146)
			(stroke
				(width 0.1524)
				(type default)
			)
			(layer "F.SilkS")
		)
		(fp_line
			(start 0.525018 3.075178)
			(end 0.525018 2.489962)
			(stroke
				(width 0.1524)
				(type default)
			)
			(layer "F.SilkS")
		)
		(fp_poly
			(pts
				(xy 0 -0.519938) (xy 0.299974 -1.420114) (xy -0.299974 -1.420114)
			)
			(stroke
				(width 0)
				(type default)
			)
			(fill yes)
			(layer "F.SilkS")
		)
		(fp_poly
			(pts
				(xy 0.525018 0.025146) (xy 0.244602 0.025146) (xy 0.244602 -0.532638) (xy -2.244598 -0.532638) (xy -2.244598 0.025146)
				(xy -2.525014 0.025146) (xy -2.525014 3.075178) (xy -2.244598 3.075178) (xy -2.244598 3.632962)
				(xy 0.244602 3.632962) (xy 0.244602 3.075178) (xy 0.525018 3.075178)
			)
			(stroke
				(width 0)
				(type default)
			)
			(fill no)
			(layer "F.CrtYd")
		)
		(fp_line
			(start -2.525014 0.025146)
			(end 0.525018 0.025146)
			(stroke
				(width 0.1)
				(type default)
			)
			(layer "F.Fab")
		)
		(fp_line
			(start -2.525014 3.075178)
			(end -2.525014 0.025146)
			(stroke
				(width 0.1)
				(type default)
			)
			(layer "F.Fab")
		)
		(fp_line
			(start 0.525018 0.025146)
			(end 0.525018 3.075178)
			(stroke
				(width 0.1)
				(type default)
			)
			(layer "F.Fab")
		)
		(fp_line
			(start 0.525018 3.075178)
			(end -2.525014 3.075178)
			(stroke
				(width 0.1)
				(type default)
			)
			(layer "F.Fab")
		)
		(fp_poly
			(pts
				(xy 0 -0.519938) (xy 0.302514 -1.427734) (xy -0.302514 -1.427734)
			)
			(stroke
				(width 0)
				(type default)
			)
			(fill yes)
			(layer "F.Fab")
		)
		(fp_text user "5"
			(at -2.123948 -0.583692 90)
			(unlocked yes)
			(layer "F.SilkS")
			(effects
				(font
					(size 0.635 0.4064)
					(thickness 0.1524)
				)
				(justify left)
			)
		)
		(fp_text user "6"
			(at -2.105914 4.059682 90)
			(unlocked yes)
			(layer "F.SilkS")
			(effects
				(font
					(size 0.635 0.4064)
					(thickness 0.1524)
				)
				(justify left)
			)
		)
		(fp_text user "1"
			(at 0.61468 -0.441198 90)
			(unlocked yes)
			(layer "F.SilkS")
			(effects
				(font
					(size 0.635 0.4064)
					(thickness 0.1524)
				)
				(justify left)
			)
		)
		(fp_text user "10"
			(at 0.750316 4.322572 90)
			(unlocked yes)
			(layer "F.SilkS")
			(effects
				(font
					(size 0.635 0.4064)
					(thickness 0.1524)
				)
				(justify left)
			)
		)
		(fp_text user "5"
			(at -2.155698 -0.695706 180)
			(unlocked yes)
			(layer "F.Fab")
			(effects
				(font
					(size 0.7874 0.5842)
					(thickness 0.000001)
				)
				(justify left)
			)
		)
		(fp_text user "6"
			(at -2.155698 3.725672 180)
			(unlocked yes)
			(layer "F.Fab")
			(effects
				(font
					(size 0.7874 0.5842)
					(thickness 0.000001)
				)
				(justify left)
			)
		)
		(fp_text user "1"
			(at 0.790702 -0.695706 180)
			(unlocked yes)
			(layer "F.Fab")
			(effects
				(font
					(size 0.7874 0.5842)
					(thickness 0.000001)
				)
				(justify left)
			)
		)
		(fp_text user "10"
			(at 1.565402 3.700272 180)
			(unlocked yes)
			(layer "F.Fab")
			(effects
				(font
					(size 0.7874 0.5842)
					(thickness 0.000001)
				)
				(justify left)
			)
		)
		(pad "1" smd rect
			(at 0 0 180)
			(size 0.2794 0.9144)
			(layers "F.Cu" "F.Mask" "F.Paste")
			(net "P1V538_BMC_NODE1")
		)
		(pad "2" smd rect
			(at -0.499872 0 180)
			(size 0.2794 0.9144)
			(layers "F.Cu" "F.Mask" "F.Paste")
			(net "P1V538_BMC_NODE1")
		)
		(pad "3" smd rect
			(at -0.999998 0 180)
			(size 0.2794 0.9144)
			(layers "F.Cu" "F.Mask" "F.Paste")
			(net "P1V538_BMC_NODE1")
		)
		(pad "4" smd rect
			(at -1.500124 0 180)
			(size 0.2794 0.9144)
			(layers "F.Cu" "F.Mask" "F.Paste")
			(net "P1V538_BMC_NODE1_ADJ")
		)
		(pad "5" smd rect
			(at -1.999996 0)
			(size 0.2794 0.9144)
			(layers "F.Cu" "F.Mask" "F.Paste")
			(net "PWRGD_NODE1_P1V538_BMC_PG")
		)
		(pad "6" smd rect
			(at -1.999996 3.100324)
			(size 0.2794 0.9144)
			(layers "F.Cu" "F.Mask" "F.Paste")
			(net "FM_CPLD_NODE1_P1V538_BMC_EN")
		)
		(pad "7" smd rect
			(at -1.500124 3.100324 180)
			(size 0.2794 0.9144)
			(layers "F.Cu" "F.Mask" "F.Paste")
			(net "P1V8_NODE1")
		)
		(pad "8" smd rect
			(at -0.999998 3.100324 180)
			(size 0.2794 0.9144)
			(layers "F.Cu" "F.Mask" "F.Paste")
			(net "P1V8_NODE1")
		)
		(pad "9" smd rect
			(at -0.499872 3.100324 180)
			(size 0.2794 0.9144)
			(layers "F.Cu" "F.Mask" "F.Paste")
			(net "P1V8_NODE1")
		)
		(pad "10" smd rect
			(at 0 3.100324 180)
			(size 0.2794 0.9144)
			(layers "F.Cu" "F.Mask" "F.Paste")
			(net "P5V_STB_NODE1")
		)
		(pad "TH" smd rect
			(at -0.999998 1.550162 270)
			(size 1.7526 2.667)
			(layers "F.Cu" "F.Mask" "F.Paste")
			(net "GND")
		)
		(zone
			(layer "F.Cu")
			(hatch none 0.5)
			(connect_pads
				(clearance 0)
			)
			(min_thickness 0.25)
			(keepout
				(tracks allowed)
				(vias not_allowed)
				(pads allowed)
				(copperpour not_allowed)
				(footprints allowed)
			)
			(placement
				(enabled no)
				(sheetname "")
			)
			(fill
				(thermal_gap 0.5)
				(thermal_bridge_width 0.5)
				(island_removal_mode 0)
			)
			(polygon
				(pts
					(xy 32.174688 -127.821182) (xy 29.126688 -127.821182) (xy 29.126688 -125.789182) (xy 32.174688 -125.789182)
					(xy 32.174688 -127.719582) (xy 32.047688 -127.719582) (xy 32.047688 -125.865382) (xy 29.228288 -125.865382)
					(xy 29.228288 -127.744982) (xy 32.174688 -127.744982)
				)
			)
		)
	)
	(footprint ""
		(layer "F.Cu")
		(at 67.241166 -96.709992 -90)
		(property "Reference" "R73"
			(at 54.98719 -28.370276 90)
			(unlocked yes)
			(layer "F.SilkS")
			(effects
				(font
					(size 0.7874 0.5842)
					(thickness 0.1524)
				)
				(justify left)
			)
		)
		(property "Value" ""
			(at 0 0 270)
			(layer "F.Fab")
			(effects
				(font
					(size 1.27 1.27)
				)
			)
		)
		(duplicate_pad_numbers_are_jumpers no)
		(fp_line
			(start -0.7874 0.4064)
			(end -0.7874 -0.4064)
			(stroke
				(width 0.1524)
				(type default)
			)
			(layer "F.SilkS")
		)
		(fp_line
			(start 0.7874 0.4064)
			(end -0.7874 0.4064)
			(stroke
				(width 0.1524)
				(type default)
			)
			(layer "F.SilkS")
		)
		(fp_line
			(start -0.7874 -0.4064)
			(end 0.7874 -0.4064)
			(stroke
				(width 0.1524)
				(type default)
			)
			(layer "F.SilkS")
		)
		(fp_line
			(start 0.7874 -0.4064)
			(end 0.7874 0.4064)
			(stroke
				(width 0.1524)
				(type default)
			)
			(layer "F.SilkS")
		)
		(fp_poly
			(pts
				(xy -0.508 0.2794) (xy -0.508 0.2286) (xy -0.635 0.2286) (xy -0.635 -0.254) (xy -0.5334 -0.254)
				(xy -0.5334 -0.2794) (xy 0.5334 -0.2794) (xy 0.5334 -0.254) (xy 0.635 -0.254) (xy 0.635 0.254) (xy 0.5334 0.254)
				(xy 0.5334 0.2794)
			)
			(stroke
				(width 0)
				(type default)
			)
			(fill no)
			(layer "F.CrtYd")
		)
		(pad "1" smd rect
			(at 0.40005 0 270)
			(size 0.4572 0.508)
			(layers "F.Cu" "F.Mask" "F.Paste")
			(net "LPC_CPU_NODE1_R_CLKOUT0")
		)
		(pad "2" smd rect
			(at -0.40005 0 270)
			(size 0.4572 0.508)
			(layers "F.Cu" "F.Mask" "F.Paste")
			(net "LPC_CPU_NODE1_CLKOUT0")
		)
	)
	(footprint ""
		(layer "F.Cu")
		(at 39.297356 -14.200124)
		(property "Reference" "PR33"
			(at -1.999996 -2.53873 0)
			(unlocked yes)
			(layer "F.SilkS")
			(effects
				(font
					(size 0.7874 0.5842)
					(thickness 0.1524)
				)
				(justify left)
			)
		)
		(property "Value" ""
			(at 0 0 0)
			(layer "F.Fab")
			(effects
				(font
					(size 1.27 1.27)
				)
			)
		)
		(duplicate_pad_numbers_are_jumpers no)
		(fp_line
			(start -0.7874 -0.4064)
			(end 0.7874 -0.4064)
			(stroke
				(width 0.1524)
				(type default)
			)
			(layer "F.SilkS")
		)
		(fp_line
			(start -0.7874 0.4064)
			(end -0.7874 -0.4064)
			(stroke
				(width 0.1524)
				(type default)
			)
			(layer "F.SilkS")
		)
		(fp_line
			(start 0.7874 -0.4064)
			(end 0.7874 0.4064)
			(stroke
				(width 0.1524)
				(type default)
			)
			(layer "F.SilkS")
		)
		(fp_line
			(start 0.7874 0.4064)
			(end -0.7874 0.4064)
			(stroke
				(width 0.1524)
				(type default)
			)
			(layer "F.SilkS")
		)
		(fp_poly
			(pts
				(xy -0.508 0.2794) (xy -0.508 0.2286) (xy -0.635 0.2286) (xy -0.635 -0.254) (xy -0.5334 -0.254)
				(xy -0.5334 -0.2794) (xy 0.5334 -0.2794) (xy 0.5334 -0.254) (xy 0.635 -0.254) (xy 0.635 0.254) (xy 0.5334 0.254)
				(xy 0.5334 0.2794)
			)
			(stroke
				(width 0)
				(type default)
			)
			(fill no)
			(layer "F.CrtYd")
		)
		(pad "1" smd rect
			(at 0.40005 0)
			(size 0.4572 0.508)
			(layers "F.Cu" "F.Mask" "F.Paste")
			(net "PV_VDDR_NODE1_MODE")
		)
		(pad "2" smd rect
			(at -0.40005 0)
			(size 0.4572 0.508)
			(layers "F.Cu" "F.Mask" "F.Paste")
			(net "GND")
		)
	)
	(footprint ""
		(layer "F.Cu")
		(at 71.014844 -156.09443 -90)
		(property "Reference" "PL12"
			(at -3.872738 -0.978916 0)
			(unlocked yes)
			(layer "F.SilkS")
			(effects
				(font
					(size 0.7874 0.5842)
					(thickness 0.1524)
				)
				(justify left)
			)
		)
		(property "Value" ""
			(at 0 0 270)
			(layer "F.Fab")
			(effects
				(font
					(size 1.27 1.27)
				)
			)
		)
		(duplicate_pad_numbers_are_jumpers no)
		(fp_line
			(start -3.350006 4.1656)
			(end -3.350006 -4.1656)
			(stroke
				(width 0.1524)
				(type default)
			)
			(layer "F.SilkS")
		)
		(fp_line
			(start 3.350006 4.1656)
			(end -3.350006 4.1656)
			(stroke
				(width 0.1524)
				(type default)
			)
			(layer "F.SilkS")
		)
		(fp_line
			(start -3.350006 -4.1656)
			(end 3.350006 -4.1656)
			(stroke
				(width 0.1524)
				(type default)
			)
			(layer "F.SilkS")
		)
		(fp_line
			(start 3.350006 -4.1656)
			(end 3.350006 4.1656)
			(stroke
				(width 0.1524)
				(type default)
			)
			(layer "F.SilkS")
		)
		(fp_poly
			(pts
				(xy -3.350006 -3.64998) (xy -1.7018 -3.64998) (xy -1.7018 -4.05257) (xy 1.7018 -4.05257) (xy 1.7018 -3.64998)
				(xy 3.350006 -3.64998) (xy 3.350006 3.64998) (xy 1.7018 3.64998) (xy 1.7018 4.05257) (xy -1.7018 4.05257)
				(xy -1.7018 3.64998) (xy -3.350006 3.64998)
			)
			(stroke
				(width 0)
				(type default)
			)
			(fill no)
			(layer "F.CrtYd")
		)
		(fp_line
			(start -3.350006 3.64998)
			(end -3.350006 -3.64998)
			(stroke
				(width 0.1)
				(type default)
			)
			(layer "F.Fab")
		)
		(fp_line
			(start 3.350006 3.64998)
			(end -3.350006 3.64998)
			(stroke
				(width 0.1)
				(type default)
			)
			(layer "F.Fab")
		)
		(fp_line
			(start -3.350006 -3.64998)
			(end 3.350006 -3.64998)
			(stroke
				(width 0.1)
				(type default)
			)
			(layer "F.Fab")
		)
		(fp_line
			(start 3.350006 -3.64998)
			(end 3.350006 3.64998)
			(stroke
				(width 0.1)
				(type default)
			)
			(layer "F.Fab")
		)
		(pad "1" smd rect
			(at 0 -2.92481 180)
			(size 2.15392 3.302)
			(layers "F.Cu" "F.Mask" "F.Paste")
			(net "SW_P5V_STB_NODE1_PH")
		)
		(pad "2" smd rect
			(at 0 2.92481 180)
			(size 2.15392 3.302)
			(layers "F.Cu" "F.Mask" "F.Paste")
			(net "P5V_STB_NODE1")
		)
	)
	(footprint ""
		(layer "F.Cu")
		(at 189.37732 -15.96898 -90)
		(property "Reference" ""
			(at 0 0 270)
			(layer "F.SilkS")
			(hide yes)
			(effects
				(font
					(size 1.27 1.27)
				)
			)
		)
		(property "Value" ""
			(at 0 0 270)
			(layer "F.Fab")
			(effects
				(font
					(size 1.27 1.27)
				)
			)
		)
		(duplicate_pad_numbers_are_jumpers no)
		(fp_poly
			(pts
				(arc
					(start 0 -1.4986)
					(mid 0 1.4986)
					(end 0 -1.4986)
				)
			)
			(stroke
				(width 0)
				(type default)
			)
			(fill no)
			(layer "F.CrtYd")
		)
		(pad "1" smd circle
			(at 0 0 270)
			(size 0.9906 0.9906)
			(layers "F.Cu" "F.Mask" "F.Paste")
			(net "Net_39")
		)
		(zone
			(layer "F.Cu")
			(hatch none 0.5)
			(connect_pads
				(clearance 0)
			)
			(min_thickness 0.25)
			(keepout
				(tracks not_allowed)
				(vias allowed)
				(pads allowed)
				(copperpour not_allowed)
				(footprints allowed)
			)
			(placement
				(enabled no)
				(sheetname "")
			)
			(fill
				(thermal_gap 0.5)
				(thermal_bridge_width 0.5)
				(island_removal_mode 0)
			)
			(polygon
				(pts
					(arc
						(start 191.00292 -15.96898)
						(mid 187.75172 -15.96898)
						(end 191.00292 -15.96898)
					)
				)
			)
		)
	)
	(footprint ""
		(layer "F.Cu")
		(at 166.801038 -79.08671 180)
		(property "Reference" "C883"
			(at -1.545336 0.064008 0)
			(unlocked yes)
			(layer "F.SilkS")
			(effects
				(font
					(size 0.7874 0.5842)
					(thickness 0.1524)
				)
				(justify left)
			)
		)
		(property "Value" ""
			(at 0 0 180)
			(layer "F.Fab")
			(effects
				(font
					(size 1.27 1.27)
				)
			)
		)
		(duplicate_pad_numbers_are_jumpers no)
		(fp_line
			(start 0.7874 0.4064)
			(end -0.7874 0.4064)
			(stroke
				(width 0.1524)
				(type default)
			)
			(layer "F.SilkS")
		)
		(fp_line
			(start 0.7874 -0.4064)
			(end 0.7874 0.4064)
			(stroke
				(width 0.1524)
				(type default)
			)
			(layer "F.SilkS")
		)
		(fp_line
			(start 0 0.381)
			(end 0 -0.381)
			(stroke
				(width 0.1524)
				(type default)
			)
			(layer "F.SilkS")
		)
		(fp_line
			(start -0.7874 0.4064)
			(end -0.7874 -0.4064)
			(stroke
				(width 0.1524)
				(type default)
			)
			(layer "F.SilkS")
		)
		(fp_line
			(start -0.7874 -0.4064)
			(end 0.7874 -0.4064)
			(stroke
				(width 0.1524)
				(type default)
			)
			(layer "F.SilkS")
		)
		(fp_poly
			(pts
				(xy -0.5334 0.254) (xy -0.635 0.254) (xy -0.635 0.2286) (xy -0.635 -0.254) (xy -0.5334 -0.254) (xy -0.5334 -0.2794)
				(xy 0.5334 -0.2794) (xy 0.5334 -0.254) (xy 0.635 -0.254) (xy 0.635 0.254) (xy 0.5334 0.254) (xy 0.5334 0.2794)
				(xy -0.508 0.2794) (xy -0.5334 0.2794)
			)
			(stroke
				(width 0)
				(type default)
			)
			(fill no)
			(layer "F.CrtYd")
		)
		(pad "1" smd rect
			(at 0.40005 0 180)
			(size 0.4572 0.508)
			(layers "F.Cu" "F.Mask" "F.Paste")
			(net "P5V_STB_NODE1")
		)
		(pad "2" smd rect
			(at -0.40005 0 180)
			(size 0.4572 0.508)
			(layers "F.Cu" "F.Mask" "F.Paste")
			(net "GND")
		)
	)
	(footprint ""
		(layer "F.Cu")
		(at 102.039166 -135.132064)
		(property "Reference" "R137"
			(at -4.413758 -8.417814 0)
			(unlocked yes)
			(layer "F.SilkS")
			(effects
				(font
					(size 0.7874 0.5842)
					(thickness 0.1524)
				)
				(justify left)
			)
		)
		(property "Value" ""
			(at 0 0 0)
			(layer "F.Fab")
			(effects
				(font
					(size 1.27 1.27)
				)
			)
		)
		(duplicate_pad_numbers_are_jumpers no)
		(fp_line
			(start -0.7874 -0.4064)
			(end 0.7874 -0.4064)
			(stroke
				(width 0.1524)
				(type default)
			)
			(layer "F.SilkS")
		)
		(fp_line
			(start -0.7874 0.4064)
			(end -0.7874 -0.4064)
			(stroke
				(width 0.1524)
				(type default)
			)
			(layer "F.SilkS")
		)
		(fp_line
			(start 0.7874 -0.4064)
			(end 0.7874 0.4064)
			(stroke
				(width 0.1524)
				(type default)
			)
			(layer "F.SilkS")
		)
		(fp_line
			(start 0.7874 0.4064)
			(end -0.7874 0.4064)
			(stroke
				(width 0.1524)
				(type default)
			)
			(layer "F.SilkS")
		)
		(fp_poly
			(pts
				(xy -0.508 0.2794) (xy -0.508 0.2286) (xy -0.635 0.2286) (xy -0.635 -0.254) (xy -0.5334 -0.254)
				(xy -0.5334 -0.2794) (xy 0.5334 -0.2794) (xy 0.5334 -0.254) (xy 0.635 -0.254) (xy 0.635 0.254) (xy 0.5334 0.254)
				(xy 0.5334 0.2794)
			)
			(stroke
				(width 0)
				(type default)
			)
			(fill no)
			(layer "F.CrtYd")
		)
		(pad "1" smd rect
			(at 0.40005 0)
			(size 0.4572 0.508)
			(layers "F.Cu" "F.Mask" "F.Paste")
			(net "SVID_CPU_NODE1_PVCCP_DAT")
		)
		(pad "2" smd rect
			(at -0.40005 0)
			(size 0.4572 0.508)
			(layers "F.Cu" "F.Mask" "F.Paste")
			(net "P1V05_NODE1")
		)
	)
)
